(kicad_pcb
	(version 20260206)
	(generator "pcbnew")
	(generator_version "10.0")
	(general
		(thickness 1.6)
		(legacy_teardrops no)
	)
	(paper "A4")
	(title_block
		(title "01162023_DA0F0TEBIF0_F0T_Expander_BD_F_brd_V02_OCP.brd")
		(comment 1 "Grand Teton / footprints 2098-2103 of 9728")
	)
	(layers
		(0 "F.Cu" signal "TOP")
		(4 "In1.Cu" signal "GND")
		(6 "In2.Cu" signal "VCC")
		(8 "In3.Cu" signal "VCC1")
		(10 "In4.Cu" signal "GND1")
		(12 "In5.Cu" signal "IN1")
		(14 "In6.Cu" signal "GND2")
		(16 "In7.Cu" signal "IN2")
		(18 "In8.Cu" signal "GND3")
		(20 "In9.Cu" signal "IN3")
		(22 "In10.Cu" signal "GND4")
		(24 "In11.Cu" signal "IN4")
		(26 "In12.Cu" signal "GND5")
		(28 "In13.Cu" signal "IN5")
		(30 "In14.Cu" signal "GND6")
		(32 "In15.Cu" signal "IN6")
		(34 "In16.Cu" signal "GND7")
		(2 "B.Cu" signal "BOTTOM")
		(9 "F.Adhes" user "F.Adhesive")
		(11 "B.Adhes" user "B.Adhesive")
		(13 "F.Paste" user "Package Geometry/Pastemask Top")
		(15 "B.Paste" user "Package Geometry/Pastemask Bottom")
		(5 "F.SilkS" user "Ref Des/Silkscreen Top")
		(7 "B.SilkS" user "Ref Des/Silkscreen Bottom")
		(1 "F.Mask" user "Board Geometry/Soldermask Top")
		(3 "B.Mask" user "Board Geometry/Soldermask Bottom")
		(17 "Dwgs.User" user "User.Drawings")
		(19 "Cmts.User" user "User.Comments")
		(21 "Eco1.User" user "User.Eco1")
		(23 "Eco2.User" user "User.Eco2")
		(25 "Edge.Cuts" user "Board Geometry/Outline")
		(27 "Margin" user)
		(31 "F.CrtYd" user "Package Geometry/Place Bound Top")
		(29 "B.CrtYd" user "Package Geometry/Place Bound Bottom")
		(35 "F.Fab" user "Ref Des/Assembly Top")
		(33 "B.Fab" user "Ref Des/Assembly Bottom")
	)
	(footprint ""
		(layer "F.Cu")
		(at 439.612024 -100.20935 90)
		(property "Reference" "U86"
			(at 0.42545 2.450846 90)
			(unlocked yes)
			(layer "F.SilkS")
			(effects
				(font
					(size 0.7874 0.5842)
					(thickness 0.1524)
				)
			)
		)
		(property "Value" ""
			(at 0 0 90)
			(layer "F.Fab")
			(effects
				(font
					(size 1.27 1.27)
				)
			)
		)
		(duplicate_pad_numbers_are_jumpers no)
		(fp_line
			(start 1.500124 -1.500124)
			(end 1.500124 -1.004062)
			(stroke
				(width 0.1524)
				(type default)
			)
			(layer "F.SilkS")
		)
		(fp_line
			(start 1.004062 -1.500124)
			(end 1.500124 -1.500124)
			(stroke
				(width 0.1524)
				(type default)
			)
			(layer "F.SilkS")
		)
		(fp_line
			(start -1.500124 -1.500124)
			(end -1.004062 -1.500124)
			(stroke
				(width 0.1524)
				(type default)
			)
			(layer "F.SilkS")
		)
		(fp_line
			(start -1.500124 -1.004062)
			(end -1.500124 -1.500124)
			(stroke
				(width 0.1524)
				(type default)
			)
			(layer "F.SilkS")
		)
		(fp_line
			(start 1.500124 1.004062)
			(end 1.500124 1.500124)
			(stroke
				(width 0.1524)
				(type default)
			)
			(layer "F.SilkS")
		)
		(fp_line
			(start 1.500124 1.500124)
			(end 1.004062 1.500124)
			(stroke
				(width 0.1524)
				(type default)
			)
			(layer "F.SilkS")
		)
		(fp_line
			(start -1.004062 1.500124)
			(end -1.500124 1.500124)
			(stroke
				(width 0.1524)
				(type default)
			)
			(layer "F.SilkS")
		)
		(fp_line
			(start -1.500124 1.500124)
			(end -1.500124 1.004062)
			(stroke
				(width 0.1524)
				(type default)
			)
			(layer "F.SilkS")
		)
		(fp_poly
			(pts
				(xy -1.956562 -2.173478) (xy -2.675128 -1.454912) (xy -1.597406 -1.095756)
			)
			(stroke
				(width 0)
				(type default)
			)
			(fill yes)
			(layer "F.SilkS")
		)
		(fp_line
			(start 1.500124 -1.500124)
			(end 1.500124 1.500124)
			(stroke
				(width 0.1)
				(type default)
			)
			(layer "F.Fab")
		)
		(fp_line
			(start -1.500124 -1.500124)
			(end 1.500124 -1.500124)
			(stroke
				(width 0.1)
				(type default)
			)
			(layer "F.Fab")
		)
		(fp_line
			(start 1.500124 1.500124)
			(end -1.500124 1.500124)
			(stroke
				(width 0.1)
				(type default)
			)
			(layer "F.Fab")
		)
		(fp_line
			(start -1.500124 1.500124)
			(end -1.500124 -1.500124)
			(stroke
				(width 0.1)
				(type default)
			)
			(layer "F.Fab")
		)
		(fp_poly
			(pts
				(xy -2.847848 -1.258062) (xy -2.847848 -0.242062) (xy -1.831848 -0.750062)
			)
			(stroke
				(width 0)
				(type default)
			)
			(fill yes)
			(layer "F.Fab")
		)
		(pad "1" smd rect
			(at -1.400048 -0.750062)
			(size 0.2286 0.6096)
			(layers "F.Cu" "F.Mask" "F.Paste")
			(net "NIC7_ADC_A1")
		)
		(pad "2" smd rect
			(at -1.400048 -0.249936)
			(size 0.2286 0.6096)
			(layers "F.Cu" "F.Mask" "F.Paste")
			(net "NIC7_ADC_A0")
		)
		(pad "3" smd rect
			(at -1.400048 0.249936)
			(size 0.2286 0.6096)
			(layers "F.Cu" "F.Mask" "F.Paste")
			(net "NIC7_ADC_ALERT_N")
		)
		(pad "4" smd rect
			(at -1.400048 0.750062)
			(size 0.2286 0.6096)
			(layers "F.Cu" "F.Mask" "F.Paste")
			(net "SMB_NIC7_ADC_SDA")
		)
		(pad "5" smd rect
			(at -0.750062 1.400048 90)
			(size 0.2286 0.6096)
			(layers "F.Cu" "F.Mask" "F.Paste")
			(net "SMB_NIC7_ADC_SCL")
		)
		(pad "6" smd rect
			(at -0.249936 1.400048 90)
			(size 0.2286 0.6096)
			(layers "F.Cu" "F.Mask" "F.Paste")
			(net "Net_8624")
		)
		(pad "7" smd rect
			(at 0.249936 1.400048 90)
			(size 0.2286 0.6096)
			(layers "F.Cu" "F.Mask" "F.Paste")
			(net "Net_8623")
		)
		(pad "8" smd rect
			(at 0.750062 1.400048 90)
			(size 0.2286 0.6096)
			(layers "F.Cu" "F.Mask" "F.Paste")
			(net "Net_8622")
		)
		(pad "9" smd rect
			(at 1.400048 0.750062)
			(size 0.2286 0.6096)
			(layers "F.Cu" "F.Mask" "F.Paste")
			(net "P3V3_AUX")
		)
		(pad "10" smd rect
			(at 1.400048 0.249936)
			(size 0.2286 0.6096)
			(layers "F.Cu" "F.Mask" "F.Paste")
			(net "GND")
		)
		(pad "11" smd rect
			(at 1.400048 -0.249936)
			(size 0.2286 0.6096)
			(layers "F.Cu" "F.Mask" "F.Paste")
			(net "P12V_NIC7_R")
		)
		(pad "12" smd rect
			(at 1.400048 -0.750062)
			(size 0.2286 0.6096)
			(layers "F.Cu" "F.Mask" "F.Paste")
			(net "P12V_NIC7_VIN_N")
		)
		(pad "13" smd rect
			(at 0.750062 -1.400048 90)
			(size 0.2286 0.6096)
			(layers "F.Cu" "F.Mask" "F.Paste")
			(net "P12V_NIC7_VIN_P")
		)
		(pad "14" smd rect
			(at 0.249936 -1.400048 90)
			(size 0.2286 0.6096)
			(layers "F.Cu" "F.Mask" "F.Paste")
			(net "Net_8621")
		)
		(pad "15" smd rect
			(at -0.249936 -1.400048 90)
			(size 0.2286 0.6096)
			(layers "F.Cu" "F.Mask" "F.Paste")
			(net "Net_8620")
		)
		(pad "16" smd rect
			(at -0.750062 -1.400048 90)
			(size 0.2286 0.6096)
			(layers "F.Cu" "F.Mask" "F.Paste")
			(net "Net_8619")
		)
		(pad "TH" smd rect
			(at 0 0 90)
			(size 1.7018 1.7018)
			(layers "F.Cu" "F.Mask" "F.Paste")
			(net "GND")
		)
		(zone
			(layer "F.Cu")
			(hatch none 0.5)
			(connect_pads
				(clearance 0)
			)
			(min_thickness 0.25)
			(keepout
				(tracks not_allowed)
				(vias allowed)
				(pads allowed)
				(copperpour not_allowed)
				(footprints allowed)
			)
			(placement
				(enabled no)
				(sheetname "")
			)
			(fill
				(thermal_gap 0.5)
				(thermal_bridge_width 0.5)
				(island_removal_mode 0)
			)
			(polygon
				(pts
					(xy 439.586624 -99.164902) (xy 438.567576 -99.164902) (xy 438.567576 -101.253798) (xy 440.656472 -101.253798)
					(xy 440.656472 -99.164902) (xy 439.612024 -99.164902) (xy 439.612024 -99.30765) (xy 440.513724 -99.30765)
					(xy 440.513724 -101.11105) (xy 438.710324 -101.11105) (xy 438.710324 -99.30765) (xy 439.586624 -99.30765)
				)
			)
		)
	)
	(footprint ""
		(layer "F.Cu")
		(at 46.659546 -61.612526)
		(property "Reference" "PD25"
			(at -3.682746 -2.648204 0)
			(unlocked yes)
			(layer "F.SilkS")
			(effects
				(font
					(size 0.7874 0.5842)
					(thickness 0.1524)
				)
				(justify left)
			)
		)
		(property "Value" ""
			(at 0 0 0)
			(layer "F.Fab")
			(effects
				(font
					(size 1.27 1.27)
				)
			)
		)
		(duplicate_pad_numbers_are_jumpers no)
		(fp_line
			(start -3.656584 -1.970024)
			(end -3.656584 1.970024)
			(stroke
				(width 0.1524)
				(type default)
			)
			(layer "F.SilkS")
		)
		(fp_line
			(start -3.656584 1.970024)
			(end 4.240784 1.970024)
			(stroke
				(width 0.1524)
				(type default)
			)
			(layer "F.SilkS")
		)
		(fp_line
			(start 4.240784 -1.970024)
			(end -3.656584 -1.970024)
			(stroke
				(width 0.1524)
				(type default)
			)
			(layer "F.SilkS")
		)
		(fp_line
			(start 4.240784 1.970024)
			(end 4.240784 -1.970024)
			(stroke
				(width 0.1524)
				(type default)
			)
			(layer "F.SilkS")
		)
		(fp_poly
			(pts
				(xy 3.580384 1.970024) (xy 3.580384 -1.970024) (xy 4.240784 -1.970024) (xy 4.240784 1.970024)
			)
			(stroke
				(width 0)
				(type default)
			)
			(fill yes)
			(layer "F.SilkS")
		)
		(fp_line
			(start -2.3749 -1.970024)
			(end -2.3749 1.970024)
			(stroke
				(width 0.1)
				(type default)
			)
			(layer "F.Fab")
		)
		(fp_line
			(start -2.3749 1.970024)
			(end 2.3749 1.970024)
			(stroke
				(width 0.1)
				(type default)
			)
			(layer "F.Fab")
		)
		(fp_line
			(start 2.3749 -1.970024)
			(end -2.3749 -1.970024)
			(stroke
				(width 0.1)
				(type default)
			)
			(layer "F.Fab")
		)
		(fp_line
			(start 2.3749 1.970024)
			(end 2.3749 -1.970024)
			(stroke
				(width 0.1)
				(type default)
			)
			(layer "F.Fab")
		)
		(fp_text user "+"
			(at -4.9784 -0.23495 0)
			(unlocked yes)
			(layer "F.Fab")
			(effects
				(font
					(size 1.905 1.4224)
					(thickness 0.1524)
				)
				(justify left)
			)
		)
		(fp_text user "-"
			(at 4.1656 -0.23495 0)
			(unlocked yes)
			(layer "F.Fab")
			(effects
				(font
					(size 1.905 1.4224)
					(thickness 0.1524)
				)
				(justify left)
			)
		)
		(pad "A" smd rect
			(at -2.450084 0)
			(size 2.159 2.2606)
			(layers "F.Cu" "F.Mask" "F.Paste")
			(net "GND")
		)
		(pad "C" smd rect
			(at 2.450084 0)
			(size 2.159 2.2606)
			(layers "F.Cu" "F.Mask" "F.Paste")
			(net "P12V_AUX")
		)
	)
	(footprint ""
		(layer "F.Cu")
		(at 359.156 -189.23)
		(property "Reference" "R4600"
			(at 0 0 0)
			(layer "F.SilkS")
			(hide yes)
			(effects
				(font
					(size 1.27 1.27)
				)
			)
		)
		(property "Value" ""
			(at 0 0 0)
			(layer "F.Fab")
			(effects
				(font
					(size 1.27 1.27)
				)
			)
		)
		(duplicate_pad_numbers_are_jumpers no)
		(fp_line
			(start -0.7874 -0.4064)
			(end 0.7874 -0.4064)
			(stroke
				(width 0.1524)
				(type default)
			)
			(layer "F.SilkS")
		)
		(fp_line
			(start -0.7874 0.4064)
			(end -0.7874 -0.4064)
			(stroke
				(width 0.1524)
				(type default)
			)
			(layer "F.SilkS")
		)
		(fp_line
			(start 0.7874 -0.4064)
			(end 0.7874 0.4064)
			(stroke
				(width 0.1524)
				(type default)
			)
			(layer "F.SilkS")
		)
		(fp_line
			(start 0.7874 0.4064)
			(end -0.7874 0.4064)
			(stroke
				(width 0.1524)
				(type default)
			)
			(layer "F.SilkS")
		)
		(fp_line
			(start -0.67945 -0.305054)
			(end -0.12065 -0.305054)
			(stroke
				(width 0.1)
				(type default)
			)
			(layer "F.Fab")
		)
		(fp_line
			(start -0.67945 0.3048)
			(end -0.67945 -0.305054)
			(stroke
				(width 0.1)
				(type default)
			)
			(layer "F.Fab")
		)
		(fp_line
			(start -0.12065 -0.305054)
			(end -0.12065 -0.2794)
			(stroke
				(width 0.1)
				(type default)
			)
			(layer "F.Fab")
		)
		(fp_line
			(start -0.12065 -0.2794)
			(end 0.12065 -0.2794)
			(stroke
				(width 0.1)
				(type default)
			)
			(layer "F.Fab")
		)
		(fp_line
			(start -0.12065 0.2794)
			(end -0.12065 0.3048)
			(stroke
				(width 0.1)
				(type default)
			)
			(layer "F.Fab")
		)
		(fp_line
			(start -0.12065 0.3048)
			(end -0.67945 0.3048)
			(stroke
				(width 0.1)
				(type default)
			)
			(layer "F.Fab")
		)
		(fp_line
			(start 0.120396 0.2794)
			(end -0.12065 0.2794)
			(stroke
				(width 0.1)
				(type default)
			)
			(layer "F.Fab")
		)
		(fp_line
			(start 0.120396 0.3048)
			(end 0.120396 0.2794)
			(stroke
				(width 0.1)
				(type default)
			)
			(layer "F.Fab")
		)
		(fp_line
			(start 0.12065 -0.3048)
			(end 0.67945 -0.3048)
			(stroke
				(width 0.1)
				(type default)
			)
			(layer "F.Fab")
		)
		(fp_line
			(start 0.12065 -0.2794)
			(end 0.12065 -0.3048)
			(stroke
				(width 0.1)
				(type default)
			)
			(layer "F.Fab")
		)
		(fp_line
			(start 0.67945 -0.3048)
			(end 0.67945 0.3048)
			(stroke
				(width 0.1)
				(type default)
			)
			(layer "F.Fab")
		)
		(fp_line
			(start 0.67945 0.3048)
			(end 0.120396 0.3048)
			(stroke
				(width 0.1)
				(type default)
			)
			(layer "F.Fab")
		)
		(pad "1" smd circle
			(at -0.40005 0)
			(size 0 0)
			(layers "F.Cu" "F.Mask" "F.Paste")
			(net "P3V3_AUX")
		)
		(pad "2" smd circle
			(at 0.40005 0)
			(size 0 0)
			(layers "F.Cu" "F.Mask" "F.Paste")
			(net "SSD2_PEX_PWR_EN_R")
		)
	)
	(footprint ""
		(layer "F.Cu")
		(at 233.524044 -139.026392)
		(property "Reference" "C2791"
			(at 0 0 0)
			(layer "F.SilkS")
			(hide yes)
			(effects
				(font
					(size 1.27 1.27)
				)
			)
		)
		(property "Value" ""
			(at 0 0 0)
			(layer "F.Fab")
			(effects
				(font
					(size 1.27 1.27)
				)
			)
		)
		(duplicate_pad_numbers_are_jumpers no)
		(fp_line
			(start -0.7874 -0.4064)
			(end 0.7874 -0.4064)
			(stroke
				(width 0.1524)
				(type default)
			)
			(layer "F.SilkS")
		)
		(fp_line
			(start -0.7874 0.4064)
			(end -0.7874 -0.4064)
			(stroke
				(width 0.1524)
				(type default)
			)
			(layer "F.SilkS")
		)
		(fp_line
			(start 0.7874 -0.4064)
			(end 0.7874 0.4064)
			(stroke
				(width 0.1524)
				(type default)
			)
			(layer "F.SilkS")
		)
		(fp_line
			(start 0.7874 0.4064)
			(end -0.7874 0.4064)
			(stroke
				(width 0.1524)
				(type default)
			)
			(layer "F.SilkS")
		)
		(fp_line
			(start -0.67945 -0.305054)
			(end -0.12065 -0.305054)
			(stroke
				(width 0.1)
				(type default)
			)
			(layer "F.Fab")
		)
		(fp_line
			(start -0.67945 0.3048)
			(end -0.67945 -0.305054)
			(stroke
				(width 0.1)
				(type default)
			)
			(layer "F.Fab")
		)
		(fp_line
			(start -0.12065 -0.305054)
			(end -0.12065 -0.2794)
			(stroke
				(width 0.1)
				(type default)
			)
			(layer "F.Fab")
		)
		(fp_line
			(start -0.12065 -0.2794)
			(end 0.12065 -0.2794)
			(stroke
				(width 0.1)
				(type default)
			)
			(layer "F.Fab")
		)
		(fp_line
			(start -0.12065 0.2794)
			(end -0.12065 0.3048)
			(stroke
				(width 0.1)
				(type default)
			)
			(layer "F.Fab")
		)
		(fp_line
			(start -0.12065 0.3048)
			(end -0.67945 0.3048)
			(stroke
				(width 0.1)
				(type default)
			)
			(layer "F.Fab")
		)
		(fp_line
			(start 0.120396 0.2794)
			(end -0.12065 0.2794)
			(stroke
				(width 0.1)
				(type default)
			)
			(layer "F.Fab")
		)
		(fp_line
			(start 0.120396 0.3048)
			(end 0.120396 0.2794)
			(stroke
				(width 0.1)
				(type default)
			)
			(layer "F.Fab")
		)
		(fp_line
			(start 0.12065 -0.3048)
			(end 0.67945 -0.3048)
			(stroke
				(width 0.1)
				(type default)
			)
			(layer "F.Fab")
		)
		(fp_line
			(start 0.12065 -0.2794)
			(end 0.12065 -0.3048)
			(stroke
				(width 0.1)
				(type default)
			)
			(layer "F.Fab")
		)
		(fp_line
			(start 0.67945 -0.3048)
			(end 0.67945 0.3048)
			(stroke
				(width 0.1)
				(type default)
			)
			(layer "F.Fab")
		)
		(fp_line
			(start 0.67945 0.3048)
			(end 0.120396 0.3048)
			(stroke
				(width 0.1)
				(type default)
			)
			(layer "F.Fab")
		)
		(pad "1" smd circle
			(at -0.40005 0)
			(size 0 0)
			(layers "F.Cu" "F.Mask" "F.Paste")
			(net "XTAL_CK440_PEX_25M_R_XIN")
		)
		(pad "2" smd circle
			(at 0.40005 0)
			(size 0 0)
			(layers "F.Cu" "F.Mask" "F.Paste")
			(net "GND")
		)
	)
	(footprint ""
		(layer "F.Cu")
		(at 90.241882 -350.098614 90)
		(property "Reference" "C156"
			(at 0 0 90)
			(layer "F.SilkS")
			(hide yes)
			(effects
				(font
					(size 1.27 1.27)
				)
			)
		)
		(property "Value" ""
			(at 0 0 90)
			(layer "F.Fab")
			(effects
				(font
					(size 1.27 1.27)
				)
			)
		)
		(duplicate_pad_numbers_are_jumpers no)
		(fp_line
			(start 0.299974 -0.150114)
			(end 0.299974 0.150114)
			(stroke
				(width 0.1)
				(type default)
			)
			(layer "F.Fab")
		)
		(fp_line
			(start -0.299974 -0.150114)
			(end 0.299974 -0.150114)
			(stroke
				(width 0.1)
				(type default)
			)
			(layer "F.Fab")
		)
		(fp_line
			(start 0.299974 0.150114)
			(end -0.299974 0.150114)
			(stroke
				(width 0.1)
				(type default)
			)
			(layer "F.Fab")
		)
		(fp_line
			(start -0.299974 0.150114)
			(end -0.299974 -0.150114)
			(stroke
				(width 0.1)
				(type default)
			)
			(layer "F.Fab")
		)
		(pad "1" smd rect
			(at -0.2667 0 90)
			(size 0.3048 0.381)
			(layers "F.Cu" "F.Mask" "F.Paste")
			(net "P5E_PEX0_STN6_TX_DN<98>")
		)
		(pad "2" smd rect
			(at 0.2667 0 90)
			(size 0.3048 0.381)
			(layers "F.Cu" "F.Mask" "F.Paste")
			(net "P5E_PEX0_STN6_TX_C_DN<98>")
		)
	)
	(footprint ""
		(layer "F.Cu")
		(at 143.030194 -297.205908 -90)
		(property "Reference" "C3225"
			(at 0 0 270)
			(layer "F.SilkS")
			(hide yes)
			(effects
				(font
					(size 1.27 1.27)
				)
			)
		)
		(property "Value" ""
			(at 0 0 270)
			(layer "F.Fab")
			(effects
				(font
					(size 1.27 1.27)
				)
			)
		)
		(duplicate_pad_numbers_are_jumpers no)
		(fp_line
			(start -1.2954 0.5842)
			(end -1.2954 -0.5842)
			(stroke
				(width 0.1524)
				(type default)
			)
			(layer "F.SilkS")
		)
		(fp_line
			(start 1.2954 0.5842)
			(end -1.2954 0.5842)
			(stroke
				(width 0.1524)
				(type default)
			)
			(layer "F.SilkS")
		)
		(fp_line
			(start -1.2954 -0.5842)
			(end 1.2954 -0.5842)
			(stroke
				(width 0.1524)
				(type default)
			)
			(layer "F.SilkS")
		)
		(fp_line
			(start 1.2954 -0.5842)
			(end 1.2954 0.5842)
			(stroke
				(width 0.1524)
				(type default)
			)
			(layer "F.SilkS")
		)
		(fp_line
			(start -0.8636 0.4572)
			(end -0.8636 0.4064)
			(stroke
				(width 0.1)
				(type default)
			)
			(layer "F.Fab")
		)
		(fp_line
			(start 0.8636 0.4572)
			(end -0.8636 0.4572)
			(stroke
				(width 0.1)
				(type default)
			)
			(layer "F.Fab")
		)
		(fp_line
			(start -1.1938 0.4064)
			(end -1.1938 -0.4064)
			(stroke
				(width 0.1)
				(type default)
			)
			(layer "F.Fab")
		)
		(fp_line
			(start -0.8636 0.4064)
			(end -1.1938 0.4064)
			(stroke
				(width 0.1)
				(type default)
			)
			(layer "F.Fab")
		)
		(fp_line
			(start 0.8636 0.4064)
			(end 0.8636 0.4572)
			(stroke
				(width 0.1)
				(type default)
			)
			(layer "F.Fab")
		)
		(fp_line
			(start 1.1938 0.4064)
			(end 0.8636 0.4064)
			(stroke
				(width 0.1)
				(type default)
			)
			(layer "F.Fab")
		)
		(fp_line
			(start -1.1938 -0.4064)
			(end -0.8636 -0.4064)
			(stroke
				(width 0.1)
				(type default)
			)
			(layer "F.Fab")
		)
		(fp_line
			(start -0.8636 -0.4064)
			(end -0.8636 -0.4572)
			(stroke
				(width 0.1)
				(type default)
			)
			(layer "F.Fab")
		)
		(fp_line
			(start 0.8636 -0.4064)
			(end 1.1938 -0.4064)
			(stroke
				(width 0.1)
				(type default)
			)
			(layer "F.Fab")
		)
		(fp_line
			(start 1.1938 -0.4064)
			(end 1.1938 0.4064)
			(stroke
				(width 0.1)
				(type default)
			)
			(layer "F.Fab")
		)
		(fp_line
			(start -0.8636 -0.4572)
			(end 0.8636 -0.4572)
			(stroke
				(width 0.1)
				(type default)
			)
			(layer "F.Fab")
		)
		(fp_line
			(start 0.8636 -0.4572)
			(end 0.8636 -0.4064)
			(stroke
				(width 0.1)
				(type default)
			)
			(layer "F.Fab")
		)
		(pad "1" smd rect
			(at -0.7366 0 180)
			(size 0.7112 0.8128)
			(layers "F.Cu" "F.Mask" "F.Paste")
			(net "P1V8_PLL0_PEX1")
		)
		(pad "2" smd rect
			(at 0.7366 0 180)
			(size 0.7112 0.8128)
			(layers "F.Cu" "F.Mask" "F.Paste")
			(net "GND")
		)
	)
)
